# S9S_MB_2U (Grand Teton) — schematic netlist excerpt (pin names and nets, part order shuffled) for the footprints in the layout excerpt that follows; sources: Cadence DE-HDL packaged netlist, KiCad conversion of 03242023_DA0F0TMBIJ0_F0T_Motherboard_J_brd_V01_OCP.brd

J5  SCONN288_ADR50017P130CC  SCONN288_ADR50017-P130CC IO  pkg DDR288S_1-1VXB  page 86
  VIN_BULK0  = P12V_S3_AUX_CPU0_NVDIMM
  RFU0  = TP_CHC_CPU0_DIMM1_FRU_0
  VIN_MGMT  = P3V3_AUX
  HSCL  = I3C_SPD_DDRABCD_CPU0_LVC1_SCL_4
  HSDA  = I3C_SPD_DDRABCD_CPU0_LVC1_SDA
  VSS0  = GND
  DQ0_A  = M_C_CPU0_SA_DQ<0>
  VSS1  = GND
  DQ1_A  = M_C_CPU0_SA_DQ<1>
  VSS2  = GND
  DQS0_A_T  = M_C_CPU0_SA_DQS_DP<0>
  DQS0_A_C  = M_C_CPU0_SA_DQS_DN<0>
  VSS3  = GND
  DQ4_A  = M_C_CPU0_SA_DQ<4>
  VSS4  = GND
  DQ5_A  = M_C_CPU0_SA_DQ<5>
  VSS5  = GND
  DQ8_A  = M_C_CPU0_SA_DQ<8>
  VSS6  = GND
  DQ9_A  = M_C_CPU0_SA_DQ<9>
  VSS7  = GND
  DQS1_A_T  = M_C_CPU0_SA_DQS_DP<1>
  DQS1_A_C  = M_C_CPU0_SA_DQS_DN<1>
  VSS8  = GND
  DQ12_A  = M_C_CPU0_SA_DQ<12>
  VSS9  = GND
  DQ13_A  = M_C_CPU0_SA_DQ<13>
  VSS10  = GND
  DQ16_A  = M_C_CPU0_SA_DQ<16>
  VSS11  = GND
  DQ17_A  = M_C_CPU0_SA_DQ<17>
  VSS12  = GND
  DQS2_A_T  = M_C_CPU0_SA_DQS_DP<2>
  DQS2_A_C  = M_C_CPU0_SA_DQS_DN<2>
  VSS13  = GND
  DQ20_A  = M_C_CPU0_SA_DQ<20>
  VSS14  = GND
  DQ21_A  = M_C_CPU0_SA_DQ<21>
  VSS15  = GND
  DQ24_A  = M_C_CPU0_SA_DQ<24>
  VSS16  = GND
  DQ25_A  = M_C_CPU0_SA_DQ<25>
  VSS17  = GND
  DQS3_A_T  = M_C_CPU0_SA_DQS_DP<3>
  DQS3_A_C  = M_C_CPU0_SA_DQS_DN<3>
  VSS18  = GND
  DQ28_A  = M_C_CPU0_SA_DQ<28>
  VSS19  = GND
  DQ29_A  = M_C_CPU0_SA_DQ<29>
  VSS20  = GND
  CB0_A  = M_C_CPU0_SA_CB<0>
  VSS21  = GND
  CB1_A  = M_C_CPU0_SA_CB<1>
  VSS22  = GND
  DQS4_A_T  = M_C_CPU0_SA_DQS_DP<4>
  DQS4_A_C  = M_C_CPU0_SA_DQS_DN<4>
  VSS23  = GND
  CB4_A  = M_C_CPU0_SA_CB<4>
  VSS24  = GND
  CB5_A  = M_C_CPU0_SA_CB<5>
  VSS25  = GND
  ALERT_N  = M_C_CPU0_ALERT_N
  VSS26  = GND
  CS0_A_N  = M_C_CPU0_SA_CS_N<0>
  VSS27  = GND
  CA0_A  = M_C_CPU0_SA_CA<0>
  VSS28  = GND
  CA2_A  = M_C_CPU0_SA_CA<2>
  VSS29  = GND
  CA4_A  = M_C_CPU0_SA_CA<4>
  VSS30  = GND
  CA6_A  = M_C_CPU0_SA_CA<6>
  VSS31  = GND
  PAR_A  = M_C_CPU0_SA_PAR
  VSS32  = GND
  CA0_B  = M_C_CPU0_SB_CA<0>
  VSS33  = GND
  CA2_B  = M_C_CPU0_SB_CA<2>
  VSS34  = GND
  CA4_B  = M_C_CPU0_SB_CA<4>
  VSS35  = GND
  CA6_B  = M_C_CPU0_SB_CA<6>
  VSS36  = GND
  CS0_B_N  = M_C_CPU0_SB_CS_N<0>
  VSS37  = GND
  \lbd||rsp_a_n\  = M_C_CPU0_SA_RSP<0>
  \lbs||rsp_b_n\  = M_C_CPU0_SB_RSP<0>
  VSS38  = GND
  CB4_B  = M_C_CPU0_SB_CB<4>
  VSS39  = GND
  CB5_B  = M_C_CPU0_SB_CB<5>
  VSS40  = GND
  \dqs9_b_t||tdqs9_b_t||dbi4_b_n\  = M_C_CPU0_SB_DQS_DP<9>
  \dqs9_b_c||tdqs9_b_c\  = M_C_CPU0_SB_DQS_DN<9>
  VSS41  = GND
  CB0_B  = M_C_CPU0_SB_CB<0>
  VSS42  = GND
  CB1_B  = M_C_CPU0_SB_CB<1>
  VSS43  = GND
  DQ0_B  = M_C_CPU0_SB_DQ<0>
  VSS44  = GND
  DQ1_B  = M_C_CPU0_SB_DQ<1>
  VSS45  = GND
  DQS0_B_T  = M_C_CPU0_SB_DQS_DP<0>
  DQS0_B_C  = M_C_CPU0_SB_DQS_DN<0>
  VSS46  = GND
  DQ4_B  = M_C_CPU0_SB_DQ<4>
  VSS47  = GND
  DQ5_B  = M_C_CPU0_SB_DQ<5>
  VSS48  = GND
  DQ8_B  = M_C_CPU0_SB_DQ<8>
  VSS49  = GND
  DQ9_B  = M_C_CPU0_SB_DQ<9>
  VSS50  = GND
  DQS1_B_T  = M_C_CPU0_SB_DQS_DP<1>
  DQS1_B_C  = M_C_CPU0_SB_DQS_DN<1>
  VSS51  = GND
  DQ12_B  = M_C_CPU0_SB_DQ<12>
  VSS52  = GND
  DQ13_B  = M_C_CPU0_SB_DQ<13>
  VSS53  = GND
  DQ16_B  = M_C_CPU0_SB_DQ<16>
  VSS54  = GND
  DQ17_B  = M_C_CPU0_SB_DQ<17>
  VSS55  = GND
  DQS2_B_T  = M_C_CPU0_SB_DQS_DP<2>
  DQS2_B_C  = M_C_CPU0_SB_DQS_DN<2>
  VSS56  = GND
  DQ20_B  = M_C_CPU0_SB_DQ<20>
  VSS57  = GND
  DQ21_B  = M_C_CPU0_SB_DQ<21>
  VSS58  = GND
  DQ24_B  = M_C_CPU0_SB_DQ<24>
  VSS59  = GND
  DQ25_B  = M_C_CPU0_SB_DQ<25>
  VSS60  = GND
  DQS3_B_T  = M_C_CPU0_SB_DQS_DP<3>
  DQS3_B_C  = M_C_CPU0_SB_DQS_DN<3>
  VSS61  = GND
  DQ28_B  = M_C_CPU0_SB_DQ<28>
  VSS62  = GND
  DQ29_B  = M_C_CPU0_SB_DQ<29>
  VSS63  = GND
  RFU1  = TP_CHC_CPU0_DIMM1_FRU_1
  VIN_BULK1  = P12V_S3_AUX_CPU0_NVDIMM
  VIN_BULK2  = P12V_S3_AUX_CPU0_NVDIMM
  \pwr_good||fail_n\  = PWRGD_CHC_CPU0_DIMM1
  HSA  = PD_CHC_CPU0_DIMM1_SAA
  RFU2  = TP_CHC_CPU0_DIMM1_FRU_2
  RFU3  = TP_CHC_CPU0_DIMM1_FRU_3
  VSS64  = GND
  DQ2_A  = M_C_CPU0_SA_DQ<2>
  VSS65  = GND
  DQ3_A  = M_C_CPU0_SA_DQ<3>
  VSS66  = GND
  \dqs5_a_c||tdqs5_a_c||dqs5_a_t||tdqs5_a_t\  = M_C_CPU0_SA_DQS_DN<5>
  \dqs5_a_t||tdqs5_a_t\  = M_C_CPU0_SA_DQS_DP<5>
  VSS67  = GND
  DQ6_A  = M_C_CPU0_SA_DQ<6>
  VSS68  = GND
  DQ7_A  = M_C_CPU0_SA_DQ<7>
  VSS69  = GND
  DQ10_A  = M_C_CPU0_SA_DQ<10>
  VSS70  = GND
  DQ11_A  = M_C_CPU0_SA_DQ<11>
  VSS71  = GND
  \dqs6_a_c||tdqs6_a_c||dqs6_a_t||tdqs6_a_t\  = M_C_CPU0_SA_DQS_DN<6>
  \dqs6_a_t||tdqs6_a_t\  = M_C_CPU0_SA_DQS_DP<6>
  VSS72  = GND
  DQ14_A  = M_C_CPU0_SA_DQ<14>
  VSS73  = GND
  DQ15_A  = M_C_CPU0_SA_DQ<15>
  VSS74  = GND
  DQ18_A  = M_C_CPU0_SA_DQ<18>
  VSS75  = GND
  DQ19_A  = M_C_CPU0_SA_DQ<19>
  VSS76  = GND
  \dqs7_a_c||tdqs7_a_c\  = M_C_CPU0_SA_DQS_DN<7>
  \dqs7_a_t||tdqs7_a_t\  = M_C_CPU0_SA_DQS_DP<7>
  VSS77  = GND
  DQ22_A  = M_C_CPU0_SA_DQ<22>
  VSS78  = GND
  DQ23_A  = M_C_CPU0_SA_DQ<23>
  VSS79  = GND
  DQ26_A  = M_C_CPU0_SA_DQ<26>
  VSS80  = GND
  DQ27_A  = M_C_CPU0_SA_DQ<27>
  VSS81  = GND
  \dqs8_a_c||tdqs8_a_c\  = M_C_CPU0_SA_DQS_DN<8>
  \dqs8_a_t||tdqs8_a_t\  = M_C_CPU0_SA_DQS_DP<8>
  VSS82  = GND
  DQ30_A  = M_C_CPU0_SA_DQ<30>
  VSS83  = GND
  DQ31_A  = M_C_CPU0_SA_DQ<31>
  VSS84  = GND
  CB2_A  = M_C_CPU0_SA_CB<2>
  VSS85  = GND
  CB3_A  = M_C_CPU0_SA_CB<3>
  VSS86  = GND
  \dqs9_a_c||tdqs9_a_c\  = M_C_CPU0_SA_DQS_DN<9>
  \dqs9_a_t||tdqs9_a_t\  = M_C_CPU0_SA_DQS_DP<9>
  VSS87  = GND
  CB6_A  = M_C_CPU0_SA_CB<6>
  VSS88  = GND
  CB7_A  = M_C_CPU0_SA_CB<7>
  VSS89  = GND
  RESET_N  = RST_M_CD_CPU0_FPGA_N
  VSS90  = GND
  CS1_A_N  = M_C_CPU0_SA_CS_N<1>
  VSS91  = GND
  CA1_A  = M_C_CPU0_SA_CA<1>
  VSS92  = GND
  CA3_A  = M_C_CPU0_SA_CA<3>
  VSS93  = GND
  CA5_A  = M_C_CPU0_SA_CA<5>
  VSS94  = GND
  CK_T  = M_C_CPU0_CLK_DP<0>
  CK_C  = M_C_CPU0_CLK_DN<0>
  VSS95  = GND
  RFU4  = TP_CHC_CPU0_DIMM1_FRU_4
  CA1_B  = M_C_CPU0_SB_CA<1>
  VSS96  = GND
  CA3_B  = M_C_CPU0_SB_CA<3>
  VSS97  = GND
  CA5_B  = M_C_CPU0_SB_CA<5>
  VSS98  = GND
  PAR_B  = M_C_CPU0_SB_PAR
  VSS99  = GND
  CS1_B_N  = M_C_CPU0_SB_CS_N<1>
  VSS100  = GND
  RFU5  = TP_CHC_CPU0_DIMM1_FRU_5
  RFU6  = TP_CHC_CPU0_DIMM1_FRU_6
  VSS101  = GND
  CB6_B  = M_C_CPU0_SB_CB<6>
  VSS102  = GND
  CB7_B  = M_C_CPU0_SB_CB<7>
  VSS103  = GND
  DQS4_B_C  = M_C_CPU0_SB_DQS_DN<4>
  DQS4_B_T  = M_C_CPU0_SB_DQS_DP<4>
  VSS104  = GND
  CB2_B  = M_C_CPU0_SB_CB<2>
  VSS105  = GND
  CB3_B  = M_C_CPU0_SB_CB<3>
  VSS106  = GND
  DQ2_B  = M_C_CPU0_SB_DQ<2>
  VSS107  = GND
  DQ3_B  = M_C_CPU0_SB_DQ<3>
  VSS108  = GND
  \dqs5_b_c||tdqs5_b_c\  = M_C_CPU0_SB_DQS_DN<5>
  \dqs5_b_t||tdqs5_b_t\  = M_C_CPU0_SB_DQS_DP<5>
  VSS109  = GND
  DQ6_B  = M_C_CPU0_SB_DQ<6>
  VSS110  = GND
  DQ7_B  = M_C_CPU0_SB_DQ<7>
  VSS111  = GND
  DQ10_B  = M_C_CPU0_SB_DQ<10>
  VSS112  = GND
  DQ11_B  = M_C_CPU0_SB_DQ<11>
  VSS113  = GND
  \dqs6_b_c||tdqs6_b_c\  = M_C_CPU0_SB_DQS_DN<6>
  \dqs6_b_t||tdqs6_b_t\  = M_C_CPU0_SB_DQS_DP<6>
  VSS114  = GND
  DQ14_B  = M_C_CPU0_SB_DQ<14>
  VSS115  = GND
  DQ15_B  = M_C_CPU0_SB_DQ<15>
  VSS116  = GND
  DQ18_B  = M_C_CPU0_SB_DQ<18>
  VSS117  = GND
  DQ19_B  = M_C_CPU0_SB_DQ<19>
  VSS118  = GND
  \dqs7_b_c||tdqs7_b_c\  = M_C_CPU0_SB_DQS_DN<7>
  \dqs7_b_t||tdqs7_b_t\  = M_C_CPU0_SB_DQS_DP<7>
  VSS119  = GND
  DQ22_B  = M_C_CPU0_SB_DQ<22>
  VSS120  = GND
  DQ23_B  = M_C_CPU0_SB_DQ<23>
  VSS121  = GND
  DQ26_B  = M_C_CPU0_SB_DQ<26>
  VSS122  = GND
  DQ27_B  = M_C_CPU0_SB_DQ<27>
  VSS123  = GND
  \dqs8_b_c||tdqs8_b_c\  = M_C_CPU0_SB_DQS_DN<8>
  \dqs8_b_t||tdqs8_b_t\  = M_C_CPU0_SB_DQS_DP<8>
  VSS124  = GND
  DQ30_B  = M_C_CPU0_SB_DQ<30>
  VSS125  = GND
  DQ31_B  = M_C_CPU0_SB_DQ<31>
  VSS126  = GND
  G1  = GND
  G2  = GND
  G3  = GND

(kicad_pcb
	(version 20260206)
	(generator "pcbnew")
	(generator_version "10.0")
	(general
		(thickness 1.6)
		(legacy_teardrops no)
	)
	(paper "A4")
	(title_block
		(title "03242023_DA0F0TMBIJ0_F0T_Motherboard_J_brd_V01_OCP.brd")
		(comment 1 "Grand Teton / footprint 885 of 6105 (J5), pads 46-91 of 291")
	)
	(layers
		(0 "F.Cu" signal "TOP")
		(4 "In1.Cu" signal "GND")
		(6 "In2.Cu" signal "IN1")
		(8 "In3.Cu" signal "GND1")
		(10 "In4.Cu" signal "IN2")
		(12 "In5.Cu" signal "GND2")
		(14 "In6.Cu" signal "IN3")
		(16 "In7.Cu" signal "GND3")
		(18 "In8.Cu" signal "VCC")
		(20 "In9.Cu" signal "VCC1")
		(22 "In10.Cu" signal "GND4")
		(24 "In11.Cu" signal "IN4")
		(26 "In12.Cu" signal "GND5")
		(28 "In13.Cu" signal "IN5")
		(30 "In14.Cu" signal "GND6")
		(32 "In15.Cu" signal "IN6")
		(34 "In16.Cu" signal "GND7")
		(2 "B.Cu" signal "BOTTOM")
		(9 "F.Adhes" user "F.Adhesive")
		(11 "B.Adhes" user "B.Adhesive")
		(13 "F.Paste" user "Package Geometry/Pastemask Top")
		(15 "B.Paste" user "Package Geometry/Pastemask Bottom")
		(5 "F.SilkS" user "Ref Des/Silkscreen Top")
		(7 "B.SilkS" user "Ref Des/Silkscreen Bottom")
		(1 "F.Mask" user "Board Geometry/Soldermask Top")
		(3 "B.Mask" user "Board Geometry/Soldermask Bottom")
		(17 "Dwgs.User" user "User.Drawings")
		(19 "Cmts.User" user "User.Comments")
		(21 "Eco1.User" user "User.Eco1")
		(23 "Eco2.User" user "User.Eco2")
		(25 "Edge.Cuts" user "Board Geometry/Outline")
		(27 "Margin" user)
		(31 "F.CrtYd" user "Package Geometry/Place Bound Top")
		(29 "B.CrtYd" user "Package Geometry/Place Bound Bottom")
		(35 "F.Fab" user "Ref Des/Assembly Top")
		(33 "B.Fab" user "Ref Des/Assembly Bottom")
	)
	(footprint ""
		(layer "F.Cu")
		(at 273.218148 -258.091686)
		(property "Reference" "J5"
			(at -3.683 -81.702148 0)
			(unlocked yes)
			(layer "F.SilkS")
			(effects
				(font
					(size 0.7874 0.5842)
					(thickness 0.1524)
				)
				(justify left)
			)
		)
		(property "Value" ""
			(at 0 0 0)
			(layer "F.Fab")
			(effects
				(font
					(size 1.27 1.27)
				)
			)
		)
		(duplicate_pad_numbers_are_jumpers no)
		(pad "46" smd rect
			(at -2.050034 -25.07488 270)
			(size 0.519938 1.4986)
			(layers "F.Cu" "F.Mask" "F.Paste")
			(net "GND")
		)
		(pad "47" smd rect
			(at -2.050034 -24.224996 270)
			(size 0.519938 1.4986)
			(layers "F.Cu" "F.Mask" "F.Paste")
			(net "M_C_CPU0_SA_DQ<28>")
		)
		(pad "48" smd rect
			(at -2.050034 -23.375112 270)
			(size 0.519938 1.4986)
			(layers "F.Cu" "F.Mask" "F.Paste")
			(net "GND")
		)
		(pad "49" smd rect
			(at -2.050034 -22.524974 270)
			(size 0.519938 1.4986)
			(layers "F.Cu" "F.Mask" "F.Paste")
			(net "M_C_CPU0_SA_DQ<29>")
		)
		(pad "50" smd rect
			(at -2.050034 -21.67509 270)
			(size 0.519938 1.4986)
			(layers "F.Cu" "F.Mask" "F.Paste")
			(net "GND")
		)
		(pad "51" smd rect
			(at -2.050034 -20.824952 270)
			(size 0.519938 1.4986)
			(layers "F.Cu" "F.Mask" "F.Paste")
			(net "M_C_CPU0_SA_CB<0>")
		)
		(pad "52" smd rect
			(at -2.050034 -19.975068 270)
			(size 0.519938 1.4986)
			(layers "F.Cu" "F.Mask" "F.Paste")
			(net "GND")
		)
		(pad "53" smd rect
			(at -2.050034 -19.12493 270)
			(size 0.519938 1.4986)
			(layers "F.Cu" "F.Mask" "F.Paste")
			(net "M_C_CPU0_SA_CB<1>")
		)
		(pad "54" smd rect
			(at -2.050034 -18.275046 270)
			(size 0.519938 1.4986)
			(layers "F.Cu" "F.Mask" "F.Paste")
			(net "GND")
		)
		(pad "55" smd rect
			(at -2.050034 -17.424908 270)
			(size 0.519938 1.4986)
			(layers "F.Cu" "F.Mask" "F.Paste")
			(net "M_C_CPU0_SA_DQS_DP<4>")
		)
		(pad "56" smd rect
			(at -2.050034 -16.575024 270)
			(size 0.519938 1.4986)
			(layers "F.Cu" "F.Mask" "F.Paste")
			(net "M_C_CPU0_SA_DQS_DN<4>")
		)
		(pad "57" smd rect
			(at -2.050034 -15.724886 270)
			(size 0.519938 1.4986)
			(layers "F.Cu" "F.Mask" "F.Paste")
			(net "GND")
		)
		(pad "58" smd rect
			(at -2.050034 -14.875002 270)
			(size 0.519938 1.4986)
			(layers "F.Cu" "F.Mask" "F.Paste")
			(net "M_C_CPU0_SA_CB<4>")
		)
		(pad "59" smd rect
			(at -2.050034 -14.025118 270)
			(size 0.519938 1.4986)
			(layers "F.Cu" "F.Mask" "F.Paste")
			(net "GND")
		)
		(pad "60" smd rect
			(at -2.050034 -13.17498 270)
			(size 0.519938 1.4986)
			(layers "F.Cu" "F.Mask" "F.Paste")
			(net "M_C_CPU0_SA_CB<5>")
		)
		(pad "61" smd rect
			(at -2.050034 -12.325096 270)
			(size 0.519938 1.4986)
			(layers "F.Cu" "F.Mask" "F.Paste")
			(net "GND")
		)
		(pad "62" smd rect
			(at -2.050034 -11.474958 270)
			(size 0.519938 1.4986)
			(layers "F.Cu" "F.Mask" "F.Paste")
			(net "M_C_CPU0_ALERT_N")
		)
		(pad "63" smd rect
			(at -2.050034 -10.625074 270)
			(size 0.519938 1.4986)
			(layers "F.Cu" "F.Mask" "F.Paste")
			(net "GND")
		)
		(pad "64" smd rect
			(at -2.050034 -9.774936 270)
			(size 0.519938 1.4986)
			(layers "F.Cu" "F.Mask" "F.Paste")
			(net "M_C_CPU0_SA_CS_N<0>")
		)
		(pad "65" smd rect
			(at -2.050034 -8.925052 270)
			(size 0.519938 1.4986)
			(layers "F.Cu" "F.Mask" "F.Paste")
			(net "GND")
		)
		(pad "66" smd rect
			(at -2.050034 -8.074914 270)
			(size 0.519938 1.4986)
			(layers "F.Cu" "F.Mask" "F.Paste")
			(net "M_C_CPU0_SA_CA<0>")
		)
		(pad "67" smd rect
			(at -2.050034 -7.22503 270)
			(size 0.519938 1.4986)
			(layers "F.Cu" "F.Mask" "F.Paste")
			(net "GND")
		)
		(pad "68" smd rect
			(at -2.050034 -6.374892 270)
			(size 0.519938 1.4986)
			(layers "F.Cu" "F.Mask" "F.Paste")
			(net "M_C_CPU0_SA_CA<2>")
		)
		(pad "69" smd rect
			(at -2.050034 -5.525008 270)
			(size 0.519938 1.4986)
			(layers "F.Cu" "F.Mask" "F.Paste")
			(net "GND")
		)
		(pad "70" smd rect
			(at -2.050034 -4.675124 270)
			(size 0.519938 1.4986)
			(layers "F.Cu" "F.Mask" "F.Paste")
			(net "M_C_CPU0_SA_CA<4>")
		)
		(pad "71" smd rect
			(at -2.050034 -3.824986 270)
			(size 0.519938 1.4986)
			(layers "F.Cu" "F.Mask" "F.Paste")
			(net "GND")
		)
		(pad "72" smd rect
			(at -2.050034 -2.975102 270)
			(size 0.519938 1.4986)
			(layers "F.Cu" "F.Mask" "F.Paste")
			(net "M_C_CPU0_SA_CA<6>")
		)
		(pad "73" smd rect
			(at -2.050034 -2.124964 270)
			(size 0.519938 1.4986)
			(layers "F.Cu" "F.Mask" "F.Paste")
			(net "GND")
		)
		(pad "74" smd rect
			(at -2.050034 -1.27508 270)
			(size 0.519938 1.4986)
			(layers "F.Cu" "F.Mask" "F.Paste")
			(net "M_C_CPU0_SA_PAR")
		)
		(pad "75" smd rect
			(at -2.050034 -0.424942 270)
			(size 0.519938 1.4986)
			(layers "F.Cu" "F.Mask" "F.Paste")
			(net "GND")
		)
		(pad "76" smd rect
			(at -2.050034 5.525008 270)
			(size 0.519938 1.4986)
			(layers "F.Cu" "F.Mask" "F.Paste")
			(net "M_C_CPU0_SB_CA<0>")
		)
		(pad "77" smd rect
			(at -2.050034 6.374892 270)
			(size 0.519938 1.4986)
			(layers "F.Cu" "F.Mask" "F.Paste")
			(net "GND")
		)
		(pad "78" smd rect
			(at -2.050034 7.22503 270)
			(size 0.519938 1.4986)
			(layers "F.Cu" "F.Mask" "F.Paste")
			(net "M_C_CPU0_SB_CA<2>")
		)
		(pad "79" smd rect
			(at -2.050034 8.074914 270)
			(size 0.519938 1.4986)
			(layers "F.Cu" "F.Mask" "F.Paste")
			(net "GND")
		)
		(pad "80" smd rect
			(at -2.050034 8.925052 270)
			(size 0.519938 1.4986)
			(layers "F.Cu" "F.Mask" "F.Paste")
			(net "M_C_CPU0_SB_CA<4>")
		)
		(pad "81" smd rect
			(at -2.050034 9.774936 270)
			(size 0.519938 1.4986)
			(layers "F.Cu" "F.Mask" "F.Paste")
			(net "GND")
		)
		(pad "82" smd rect
			(at -2.050034 10.625074 270)
			(size 0.519938 1.4986)
			(layers "F.Cu" "F.Mask" "F.Paste")
			(net "M_C_CPU0_SB_CA<6>")
		)
		(pad "83" smd rect
			(at -2.050034 11.474958 270)
			(size 0.519938 1.4986)
			(layers "F.Cu" "F.Mask" "F.Paste")
			(net "GND")
		)
		(pad "84" smd rect
			(at -2.050034 12.325096 270)
			(size 0.519938 1.4986)
			(layers "F.Cu" "F.Mask" "F.Paste")
			(net "M_C_CPU0_SB_CS_N<0>")
		)
		(pad "85" smd rect
			(at -2.050034 13.17498 270)
			(size 0.519938 1.4986)
			(layers "F.Cu" "F.Mask" "F.Paste")
			(net "GND")
		)
		(pad "86" smd rect
			(at -2.050034 14.025118 270)
			(size 0.519938 1.4986)
			(layers "F.Cu" "F.Mask" "F.Paste")
			(net "M_C_CPU0_SA_RSP<0>")
		)
		(pad "87" smd rect
			(at -2.050034 14.875002 270)
			(size 0.519938 1.4986)
			(layers "F.Cu" "F.Mask" "F.Paste")
			(net "M_C_CPU0_SB_RSP<0>")
		)
		(pad "88" smd rect
			(at -2.050034 15.724886 270)
			(size 0.519938 1.4986)
			(layers "F.Cu" "F.Mask" "F.Paste")
			(net "GND")
		)
		(pad "89" smd rect
			(at -2.050034 16.575024 270)
			(size 0.519938 1.4986)
			(layers "F.Cu" "F.Mask" "F.Paste")
			(net "M_C_CPU0_SB_CB<4>")
		)
		(pad "90" smd rect
			(at -2.050034 17.424908 270)
			(size 0.519938 1.4986)
			(layers "F.Cu" "F.Mask" "F.Paste")
			(net "GND")
		)
		(pad "91" smd rect
			(at -2.050034 18.275046 270)
			(size 0.519938 1.4986)
			(layers "F.Cu" "F.Mask" "F.Paste")
			(net "M_C_CPU0_SB_CB<5>")
		)
	)
)
